(kicad_pcb
	(version 20260206)
	(generator "pcbnew")
	(generator_version "10.0")
	(general
		(thickness 1.6)
		(legacy_teardrops no)
	)
	(paper "A4")
	(title_block
		(title "03242023_DA0F0TMBIJ0_F0T_Motherboard_J_brd_V01_OCP.brd")
		(comment 1 "Grand Teton / footprint 3039 of 6105 (U2), pads 750-854 of 4677")
	)
	(layers
		(0 "F.Cu" signal "TOP")
		(4 "In1.Cu" signal "GND")
		(6 "In2.Cu" signal "IN1")
		(8 "In3.Cu" signal "GND1")
		(10 "In4.Cu" signal "IN2")
		(12 "In5.Cu" signal "GND2")
		(14 "In6.Cu" signal "IN3")
		(16 "In7.Cu" signal "GND3")
		(18 "In8.Cu" signal "VCC")
		(20 "In9.Cu" signal "VCC1")
		(22 "In10.Cu" signal "GND4")
		(24 "In11.Cu" signal "IN4")
		(26 "In12.Cu" signal "GND5")
		(28 "In13.Cu" signal "IN5")
		(30 "In14.Cu" signal "GND6")
		(32 "In15.Cu" signal "IN6")
		(34 "In16.Cu" signal "GND7")
		(2 "B.Cu" signal "BOTTOM")
		(9 "F.Adhes" user "F.Adhesive")
		(11 "B.Adhes" user "B.Adhesive")
		(13 "F.Paste" user "Package Geometry/Pastemask Top")
		(15 "B.Paste" user "Package Geometry/Pastemask Bottom")
		(5 "F.SilkS" user "Ref Des/Silkscreen Top")
		(7 "B.SilkS" user "Ref Des/Silkscreen Bottom")
		(1 "F.Mask" user "Board Geometry/Soldermask Top")
		(3 "B.Mask" user "Board Geometry/Soldermask Bottom")
		(17 "Dwgs.User" user "User.Drawings")
		(19 "Cmts.User" user "User.Comments")
		(21 "Eco1.User" user "User.Eco1")
		(23 "Eco2.User" user "User.Eco2")
		(25 "Edge.Cuts" user "Board Geometry/Outline")
		(27 "Margin" user)
		(31 "F.CrtYd" user "Package Geometry/Place Bound Top")
		(29 "B.CrtYd" user "Package Geometry/Place Bound Bottom")
		(35 "F.Fab" user "Ref Des/Assembly Top")
		(33 "B.Fab" user "Ref Des/Assembly Bottom")
	)
	(footprint ""
		(layer "F.Cu")
		(at 359.870248 -251.76988 90)
		(property "Reference" "U2"
			(at -74.416158 -44.488608 0)
			(unlocked yes)
			(layer "F.SilkS")
			(effects
				(font
					(size 1.6002 1.1938)
					(thickness 0.1524)
				)
				(justify left)
			)
		)
		(property "Value" ""
			(at 0 0 90)
			(layer "F.Fab")
			(effects
				(font
					(size 1.27 1.27)
				)
			)
		)
		(duplicate_pad_numbers_are_jumpers no)
		(pad "AU7" smd circle
			(at -32.541718 -10.157714 270)
			(size 0.4318 0.4318)
			(layers "F.Cu" "F.Mask" "F.Paste")
			(net "PVCCD_HV_CPU0")
		)
		(pad "AU9" smd circle
			(at -30.914086 -10.157714 270)
			(size 0.4318 0.4318)
			(layers "F.Cu" "F.Mask" "F.Paste")
			(net "P5E_CPU0_PE0_RX_DN<13>")
		)
		(pad "AU11" smd circle
			(at -29.2862 -10.157714 270)
			(size 0.4318 0.4318)
			(layers "F.Cu" "F.Mask" "F.Paste")
			(net "VSENSE_PVCCFA_EHV_CPU0_DP")
		)
		(pad "AU13" smd circle
			(at -27.658314 -10.157714 270)
			(size 0.4318 0.4318)
			(layers "F.Cu" "F.Mask" "F.Paste")
			(net "P5E_CPU0_PE0_TX_DN<12>")
		)
		(pad "AU15" smd circle
			(at -26.030682 -10.157714 270)
			(size 0.4318 0.4318)
			(layers "F.Cu" "F.Mask" "F.Paste")
			(net "PVCCFA_EHV_FIVRA_CPU0")
		)
		(pad "AU17" smd circle
			(at -24.402796 -10.157714 270)
			(size 0.4318 0.4318)
			(layers "F.Cu" "F.Mask" "F.Paste")
			(net "PU_CPU0_FRMAGENT")
		)
		(pad "AU19" smd circle
			(at -22.77491 -10.157714 270)
			(size 0.4318 0.4318)
			(layers "F.Cu" "F.Mask" "F.Paste")
			(net "H_CPU0_PROCHOT_LVC1_N")
		)
		(pad "AU21" smd circle
			(at -21.147278 -10.157714 270)
			(size 0.4318 0.4318)
			(layers "F.Cu" "F.Mask" "F.Paste")
			(net "H_CPU0_MEMHOT_IN_LVC1_N")
		)
		(pad "AU23" smd circle
			(at -19.519392 -10.157714 270)
			(size 0.4318 0.4318)
			(layers "F.Cu" "F.Mask" "F.Paste")
			(net "PU_CPU0_SAFE_MODE_BOOT")
		)
		(pad "AU25" smd circle
			(at -17.89176 -10.157714 270)
			(size 0.4318 0.4318)
			(layers "F.Cu" "F.Mask" "F.Paste")
			(net "NC_CPU0_VIEWPIN_DIE00<2>")
		)
		(pad "AU27" smd circle
			(at -16.263874 -10.157714 270)
			(size 0.4318 0.4318)
			(layers "F.Cu" "F.Mask" "F.Paste")
			(net "GND")
		)
		(pad "AU29" smd circle
			(at -14.635988 -10.157714 270)
			(size 0.4318 0.4318)
			(layers "F.Cu" "F.Mask" "F.Paste")
			(net "CLK_100M_DB2000_CPU0_BCLK2_DN")
		)
		(pad "AU31" smd circle
			(at -13.008356 -10.157714 270)
			(size 0.4318 0.4318)
			(layers "F.Cu" "F.Mask" "F.Paste")
			(net "GND")
		)
		(pad "AU33" smd circle
			(at -11.380724 -10.157714 270)
			(size 0.4318 0.4318)
			(layers "F.Cu" "F.Mask" "F.Paste")
			(net "NC_CPU0_DDR23_VIEWDIG1")
		)
		(pad "AU35" smd circle
			(at -9.752838 -10.157714 270)
			(size 0.4318 0.4318)
			(layers "F.Cu" "F.Mask" "F.Paste")
			(net "PVCCD_HV_CPU0")
		)
		(pad "AU37" smd circle
			(at -8.124952 -10.157714 270)
			(size 0.4318 0.4318)
			(layers "F.Cu" "F.Mask" "F.Paste")
			(net "GND")
		)
		(pad "AU39" smd circle
			(at -6.49732 -10.157714 270)
			(size 0.4318 0.4318)
			(layers "F.Cu" "F.Mask" "F.Paste")
			(net "GND")
		)
		(pad "AU41" smd circle
			(at -4.869434 -10.157714 270)
			(size 0.4318 0.4318)
			(layers "F.Cu" "F.Mask" "F.Paste")
			(net "GND")
		)
		(pad "AU43" smd circle
			(at -3.241802 -10.157714 270)
			(size 0.4318 0.4318)
			(layers "F.Cu" "F.Mask" "F.Paste")
			(net "M_A_CPU0_SA_RSP<1>")
		)
		(pad "AU45" smd circle
			(at -1.613916 -10.157714 270)
			(size 0.4318 0.4318)
			(layers "F.Cu" "F.Mask" "F.Paste")
			(net "GND")
		)
		(pad "AU48" smd circle
			(at 2.427732 -10.047732 270)
			(size 0.4318 0.4318)
			(layers "F.Cu" "F.Mask" "F.Paste")
			(net "GND")
		)
		(pad "AU50" smd circle
			(at 4.055618 -10.047732 270)
			(size 0.4318 0.4318)
			(layers "F.Cu" "F.Mask" "F.Paste")
			(net "RST_CPU0_DRAM_AB_N")
		)
		(pad "AU52" smd circle
			(at 5.68325 -10.047732 270)
			(size 0.4318 0.4318)
			(layers "F.Cu" "F.Mask" "F.Paste")
			(net "TP_CPU0_SPARE5")
		)
		(pad "AU54" smd circle
			(at 7.311136 -10.047732 270)
			(size 0.4318 0.4318)
			(layers "F.Cu" "F.Mask" "F.Paste")
			(net "PVCCD_HV_CPU0")
		)
		(pad "AU56" smd circle
			(at 8.939022 -10.047732 270)
			(size 0.4318 0.4318)
			(layers "F.Cu" "F.Mask" "F.Paste")
			(net "NC_CPU0_DDR01_VIEWDIG1")
		)
		(pad "AU58" smd circle
			(at 10.566654 -10.047732 270)
			(size 0.4318 0.4318)
			(layers "F.Cu" "F.Mask" "F.Paste")
			(net "NC_CPU0_DDR01_VIEWDIG0")
		)
		(pad "AU60" smd circle
			(at 12.19454 -10.047732 270)
			(size 0.4318 0.4318)
			(layers "F.Cu" "F.Mask" "F.Paste")
			(net "PVCCFA_EHV_CPU0")
		)
		(pad "AU62" smd circle
			(at 13.822426 -10.047732 270)
			(size 0.4318 0.4318)
			(layers "F.Cu" "F.Mask" "F.Paste")
			(net "TP_SPI_IBL_CPU0_TPM_CLK")
		)
		(pad "AU64" smd circle
			(at 15.450058 -10.047732 270)
			(size 0.4318 0.4318)
			(layers "F.Cu" "F.Mask" "F.Paste")
			(net "TP_ESPI_IBL_CPU0_IO2_LVC1")
		)
		(pad "AU66" smd circle
			(at 17.07769 -10.047732 270)
			(size 0.4318 0.4318)
			(layers "F.Cu" "F.Mask" "F.Paste")
			(net "NC_CPU0_PE4_APROBE<1>")
		)
		(pad "AU68" smd circle
			(at 18.705576 -10.047732 270)
			(size 0.4318 0.4318)
			(layers "F.Cu" "F.Mask" "F.Paste")
			(net "NC_CPU0_UPI2_APROBE<0>")
		)
		(pad "AU70" smd circle
			(at 20.333462 -10.047732 270)
			(size 0.4318 0.4318)
			(layers "F.Cu" "F.Mask" "F.Paste")
			(net "GND")
		)
		(pad "AU72" smd circle
			(at 21.961094 -10.047732 270)
			(size 0.4318 0.4318)
			(layers "F.Cu" "F.Mask" "F.Paste")
			(net "GND")
		)
		(pad "AU74" smd circle
			(at 23.58898 -10.047732 270)
			(size 0.4318 0.4318)
			(layers "F.Cu" "F.Mask" "F.Paste")
			(net "GND")
		)
		(pad "AU76" smd circle
			(at 25.216612 -10.047732 270)
			(size 0.4318 0.4318)
			(layers "F.Cu" "F.Mask" "F.Paste")
			(net "GND")
		)
		(pad "AU78" smd circle
			(at 26.844498 -10.047732 270)
			(size 0.4318 0.4318)
			(layers "F.Cu" "F.Mask" "F.Paste")
			(net "UPI_CPU0_CPU1_P2P2_DN<12>")
		)
		(pad "AU80" smd circle
			(at 28.472384 -10.047732 270)
			(size 0.4318 0.4318)
			(layers "F.Cu" "F.Mask" "F.Paste")
			(net "GND")
		)
		(pad "AU82" smd circle
			(at 30.100016 -10.047732 270)
			(size 0.4318 0.4318)
			(layers "F.Cu" "F.Mask" "F.Paste")
			(net "UPI_CPU0_CPU1_P2P2_DP<7>")
		)
		(pad "AU84" smd circle
			(at 31.727902 -10.047732 270)
			(size 0.4318 0.4318)
			(layers "F.Cu" "F.Mask" "F.Paste")
			(net "GND")
		)
		(pad "AU86" smd circle
			(at 33.355534 -10.047732 270)
			(size 0.4318 0.4318)
			(layers "F.Cu" "F.Mask" "F.Paste")
			(net "P5E_CPU0_PE4_TX_DN<13>")
		)
		(pad "AU88" smd circle
			(at 34.98342 -10.047732 270)
			(size 0.4318 0.4318)
			(layers "F.Cu" "F.Mask" "F.Paste")
			(net "GND")
		)
		(pad "AU90" smd circle
			(at 36.611306 -10.047732 270)
			(size 0.4318 0.4318)
			(layers "F.Cu" "F.Mask" "F.Paste")
			(net "P5E_CPU0_PE4_RX_DP<13>")
		)
		(pad "AV2" smd circle
			(at -36.611306 -9.688068 270)
			(size 0.4318 0.4318)
			(layers "F.Cu" "F.Mask" "F.Paste")
			(net "UPI_CPU0_CPU1_P0P1_DP<14>")
		)
		(pad "AV4" smd circle
			(at -34.98342 -9.688068 270)
			(size 0.4318 0.4318)
			(layers "F.Cu" "F.Mask" "F.Paste")
			(net "GND")
		)
		(pad "AV6" smd circle
			(at -33.355534 -9.688068 270)
			(size 0.4318 0.4318)
			(layers "F.Cu" "F.Mask" "F.Paste")
			(net "UPI_CPU1_CPU0_P1P0_DP<14>")
		)
		(pad "AV8" smd circle
			(at -31.727902 -9.688068 270)
			(size 0.4318 0.4318)
			(layers "F.Cu" "F.Mask" "F.Paste")
			(net "GND")
		)
		(pad "AV10" smd circle
			(at -30.100016 -9.688068 270)
			(size 0.4318 0.4318)
			(layers "F.Cu" "F.Mask" "F.Paste")
			(net "P5E_CPU0_PE0_RX_DN<14>")
		)
		(pad "AV12" smd circle
			(at -28.472384 -9.688068 270)
			(size 0.4318 0.4318)
			(layers "F.Cu" "F.Mask" "F.Paste")
			(net "GND")
		)
		(pad "AV14" smd circle
			(at -26.844498 -9.688068 270)
			(size 0.4318 0.4318)
			(layers "F.Cu" "F.Mask" "F.Paste")
			(net "P5E_CPU0_PE0_TX_DN<13>")
		)
		(pad "AV16" smd circle
			(at -25.216612 -9.688068 270)
			(size 0.4318 0.4318)
			(layers "F.Cu" "F.Mask" "F.Paste")
			(net "GND")
		)
		(pad "AV18" smd circle
			(at -23.58898 -9.688068 270)
			(size 0.4318 0.4318)
			(layers "F.Cu" "F.Mask" "F.Paste")
			(net "H_CPU0_NMI_LVC1_N")
		)
		(pad "AV20" smd circle
			(at -21.961094 -9.688068 270)
			(size 0.4318 0.4318)
			(layers "F.Cu" "F.Mask" "F.Paste")
			(net "PWRGD_CPU0_LVC1")
		)
		(pad "AV22" smd circle
			(at -20.333462 -9.688068 270)
			(size 0.4318 0.4318)
			(layers "F.Cu" "F.Mask" "F.Paste")
			(net "H_CPU0_PREQ_QS_GTL_R_N")
		)
		(pad "AV24" smd circle
			(at -18.705576 -9.688068 270)
			(size 0.4318 0.4318)
			(layers "F.Cu" "F.Mask" "F.Paste")
			(net "H_CPU0_MEMTRIP_LVC1_R_N")
		)
		(pad "AV26" smd circle
			(at -17.07769 -9.688068 270)
			(size 0.4318 0.4318)
			(layers "F.Cu" "F.Mask" "F.Paste")
			(net "NC_CPU0_VIEWPIN_DIE00<3>")
		)
		(pad "AV28" smd circle
			(at -15.450058 -9.688068 270)
			(size 0.4318 0.4318)
			(layers "F.Cu" "F.Mask" "F.Paste")
			(net "CLK_100M_DB2000_CPU0_BCLK2_DP")
		)
		(pad "AV30" smd circle
			(at -13.822426 -9.688068 270)
			(size 0.4318 0.4318)
			(layers "F.Cu" "F.Mask" "F.Paste")
			(net "CLK_100M_DB2000_CPU0_BCLK0_DP")
		)
		(pad "AV32" smd circle
			(at -12.19454 -9.688068 270)
			(size 0.4318 0.4318)
			(layers "F.Cu" "F.Mask" "F.Paste")
			(net "NC_CPU0_DDR23_VIEWDIG0")
		)
		(pad "AV34" smd circle
			(at -10.566654 -9.688068 270)
			(size 0.4318 0.4318)
			(layers "F.Cu" "F.Mask" "F.Paste")
			(net "PVCCD_HV_CPU0")
		)
		(pad "AV36" smd circle
			(at -8.939022 -9.688068 270)
			(size 0.4318 0.4318)
			(layers "F.Cu" "F.Mask" "F.Paste")
			(net "PVCCD_HV_CPU0")
		)
		(pad "AV38" smd circle
			(at -7.311136 -9.688068 270)
			(size 0.4318 0.4318)
			(layers "F.Cu" "F.Mask" "F.Paste")
			(net "NC_CPU0_THERMADC")
		)
		(pad "AV40" smd circle
			(at -5.68325 -9.688068 270)
			(size 0.4318 0.4318)
			(layers "F.Cu" "F.Mask" "F.Paste")
			(net "NC_CPU0_THERMADA")
		)
		(pad "AV42" smd circle
			(at -4.055618 -9.688068 270)
			(size 0.4318 0.4318)
			(layers "F.Cu" "F.Mask" "F.Paste")
			(net "M_A_CPU0_SB_RSP<1>")
		)
		(pad "AV44" smd circle
			(at -2.427732 -9.688068 270)
			(size 0.4318 0.4318)
			(layers "F.Cu" "F.Mask" "F.Paste")
			(net "M_A_CPU0_SB_RSP<0>")
		)
		(pad "AV47" smd circle
			(at 1.613916 -9.578086 270)
			(size 0.4318 0.4318)
			(layers "F.Cu" "F.Mask" "F.Paste")
			(net "M_D_CPU0_ALERT_N")
		)
		(pad "AV49" smd circle
			(at 3.241802 -9.578086 270)
			(size 0.4318 0.4318)
			(layers "F.Cu" "F.Mask" "F.Paste")
			(net "M_B_CPU0_ALERT_N")
		)
		(pad "AV51" smd circle
			(at 4.869434 -9.578086 270)
			(size 0.4318 0.4318)
			(layers "F.Cu" "F.Mask" "F.Paste")
			(net "RST_CPU0_DRAM_CD_N")
		)
		(pad "AV53" smd circle
			(at 6.49732 -9.578086 270)
			(size 0.4318 0.4318)
			(layers "F.Cu" "F.Mask" "F.Paste")
			(net "PVCCD_HV_CPU0")
		)
		(pad "AV55" smd circle
			(at 8.124952 -9.578086 270)
			(size 0.4318 0.4318)
			(layers "F.Cu" "F.Mask" "F.Paste")
			(net "PVCCD_HV_CPU0")
		)
		(pad "AV57" smd circle
			(at 9.752838 -9.578086 270)
			(size 0.4318 0.4318)
			(layers "F.Cu" "F.Mask" "F.Paste")
			(net "FM_CPU_FBRK_DEBUG_R_N")
		)
		(pad "AV59" smd circle
			(at 11.380724 -9.578086 270)
			(size 0.4318 0.4318)
			(layers "F.Cu" "F.Mask" "F.Paste")
			(net "TP_EV_CPU0_EXT_BGREF")
		)
		(pad "AV61" smd circle
			(at 13.008356 -9.578086 270)
			(size 0.4318 0.4318)
			(layers "F.Cu" "F.Mask" "F.Paste")
			(net "PVCCFA_EHV_CPU0")
		)
		(pad "AV63" smd circle
			(at 14.635988 -9.578086 270)
			(size 0.4318 0.4318)
			(layers "F.Cu" "F.Mask" "F.Paste")
			(net "TP_SPI_S3M_CPU0_CS1_LVC1_R_N")
		)
		(pad "AV65" smd circle
			(at 16.263874 -9.578086 270)
			(size 0.4318 0.4318)
			(layers "F.Cu" "F.Mask" "F.Paste")
			(net "NC_CPU0_MDFI_DIE01_EW0")
		)
		(pad "AV67" smd circle
			(at 17.89176 -9.578086 270)
			(size 0.4318 0.4318)
			(layers "F.Cu" "F.Mask" "F.Paste")
			(net "NC_CPU0_PE4_APROBE<0>")
		)
		(pad "AV69" smd circle
			(at 19.519392 -9.578086 270)
			(size 0.4318 0.4318)
			(layers "F.Cu" "F.Mask" "F.Paste")
			(net "FM_S3M_CPU0_LVC1_GPIO_2")
		)
		(pad "AV71" smd circle
			(at 21.147278 -9.578086 270)
			(size 0.4318 0.4318)
			(layers "F.Cu" "F.Mask" "F.Paste")
			(net "FM_S3M_CPU0_LVC1_GPIO_1")
		)
		(pad "AV73" smd circle
			(at 22.77491 -9.578086 270)
			(size 0.4318 0.4318)
			(layers "F.Cu" "F.Mask" "F.Paste")
			(net "UPI_CPU1_CPU0_P2P2_DN<10>")
		)
		(pad "AV75" smd circle
			(at 24.402796 -9.578086 270)
			(size 0.4318 0.4318)
			(layers "F.Cu" "F.Mask" "F.Paste")
			(net "UPI_CPU1_CPU0_P2P2_DN<7>")
		)
		(pad "AV77" smd circle
			(at 26.030682 -9.578086 270)
			(size 0.4318 0.4318)
			(layers "F.Cu" "F.Mask" "F.Paste")
			(net "GND")
		)
		(pad "AV79" smd circle
			(at 27.658314 -9.578086 270)
			(size 0.4318 0.4318)
			(layers "F.Cu" "F.Mask" "F.Paste")
			(net "UPI_CPU0_CPU1_P2P2_DP<12>")
		)
		(pad "AV81" smd circle
			(at 29.2862 -9.578086 270)
			(size 0.4318 0.4318)
			(layers "F.Cu" "F.Mask" "F.Paste")
			(net "UPI_CPU0_CPU1_P2P2_DN<7>")
		)
		(pad "AV83" smd circle
			(at 30.914086 -9.578086 270)
			(size 0.4318 0.4318)
			(layers "F.Cu" "F.Mask" "F.Paste")
			(net "UPI_CPU0_CPU1_P2P2_DP<8>")
		)
		(pad "AV85" smd circle
			(at 32.541718 -9.578086 270)
			(size 0.4318 0.4318)
			(layers "F.Cu" "F.Mask" "F.Paste")
			(net "P5E_CPU0_PE4_TX_DP<13>")
		)
		(pad "AV87" smd circle
			(at 34.169604 -9.578086 270)
			(size 0.4318 0.4318)
			(layers "F.Cu" "F.Mask" "F.Paste")
			(net "GND")
		)
		(pad "AV89" smd circle
			(at 35.797236 -9.578086 270)
			(size 0.4318 0.4318)
			(layers "F.Cu" "F.Mask" "F.Paste")
			(net "P5E_CPU0_PE4_RX_DN<13>")
		)
		(pad "AV91" smd oval
			(at 37.425122 -9.578086)
			(size 0.381 0.4826)
			(drill
				(offset 0 -0.0508)
			)
			(layers "F.Cu" "F.Mask" "F.Paste")
			(net "GND")
		)
		(pad "AW1" smd oval
			(at -37.425122 -9.217914 180)
			(size 0.381 0.4826)
			(drill
				(offset 0 -0.0508)
			)
			(layers "F.Cu" "F.Mask" "F.Paste")
			(net "GND")
		)
		(pad "AW3" smd circle
			(at -35.797236 -9.217914 270)
			(size 0.4318 0.4318)
			(layers "F.Cu" "F.Mask" "F.Paste")
			(net "UPI_CPU0_CPU1_P0P1_DN<15>")
		)
		(pad "AW5" smd circle
			(at -34.169604 -9.217914 270)
			(size 0.4318 0.4318)
			(layers "F.Cu" "F.Mask" "F.Paste")
			(net "GND")
		)
		(pad "AW7" smd circle
			(at -32.541718 -9.217914 270)
			(size 0.4318 0.4318)
			(layers "F.Cu" "F.Mask" "F.Paste")
			(net "UPI_CPU1_CPU0_P1P0_DN<14>")
		)
		(pad "AW9" smd circle
			(at -30.914086 -9.217914 270)
			(size 0.4318 0.4318)
			(layers "F.Cu" "F.Mask" "F.Paste")
			(net "GND")
		)
		(pad "AW11" smd circle
			(at -29.2862 -9.217914 270)
			(size 0.4318 0.4318)
			(layers "F.Cu" "F.Mask" "F.Paste")
			(net "P5E_CPU0_PE0_RX_DP<14>")
		)
		(pad "AW13" smd circle
			(at -27.658314 -9.217914 270)
			(size 0.4318 0.4318)
			(layers "F.Cu" "F.Mask" "F.Paste")
			(net "GND")
		)
		(pad "AW15" smd circle
			(at -26.030682 -9.217914 270)
			(size 0.4318 0.4318)
			(layers "F.Cu" "F.Mask" "F.Paste")
			(net "P5E_CPU0_PE0_TX_DP<13>")
		)
		(pad "AW17" smd circle
			(at -24.402796 -9.217914 270)
			(size 0.4318 0.4318)
			(layers "F.Cu" "F.Mask" "F.Paste")
			(net "PD_CPU0_DMIMODE_OVERRIDE")
		)
		(pad "AW19" smd circle
			(at -22.77491 -9.217914 270)
			(size 0.4318 0.4318)
			(layers "F.Cu" "F.Mask" "F.Paste")
			(net "TP_FM_IBL_WAKE_CPU0_N")
		)
		(pad "AW21" smd circle
			(at -21.147278 -9.217914 270)
			(size 0.4318 0.4318)
			(layers "F.Cu" "F.Mask" "F.Paste")
			(net "GND")
		)
		(pad "AW23" smd circle
			(at -19.519392 -9.217914 270)
			(size 0.4318 0.4318)
			(layers "F.Cu" "F.Mask" "F.Paste")
			(net "GND")
		)
		(pad "AW25" smd circle
			(at -17.89176 -9.217914 270)
			(size 0.4318 0.4318)
			(layers "F.Cu" "F.Mask" "F.Paste")
			(net "GND")
		)
		(pad "AW60" smd circle
			(at 12.19454 -9.107932 270)
			(size 0.4318 0.4318)
			(layers "F.Cu" "F.Mask" "F.Paste")
			(net "PVCCFA_EHV_CPU0")
		)
		(pad "AW62" smd circle
			(at 13.822426 -9.107932 270)
			(size 0.4318 0.4318)
			(layers "F.Cu" "F.Mask" "F.Paste")
			(net "GND")
		)
		(pad "AW64" smd circle
			(at 15.450058 -9.107932 270)
			(size 0.4318 0.4318)
			(layers "F.Cu" "F.Mask" "F.Paste")
			(net "TP_SPI_S3M_CPU0_IO1_LVC1_R")
		)
		(pad "AW66" smd circle
			(at 17.07769 -9.107932 270)
			(size 0.4318 0.4318)
			(layers "F.Cu" "F.Mask" "F.Paste")
			(net "GND")
		)
		(pad "AW68" smd circle
			(at 18.705576 -9.107932 270)
			(size 0.4318 0.4318)
			(layers "F.Cu" "F.Mask" "F.Paste")
			(net "GND")
		)
	)
)
